# BASEBOARD_FAB2 (Tioga Pass) — schematic netlist excerpt (pin names and nets, part order shuffled) for the footprints in the layout excerpt that follows; sources: Cadence DE-HDL packaged netlist, KiCad conversion of Wiwynn_Tioga_Pass_MB.brd

C8C6  CAP  10UF 6.3V 20% X6S  pkg 0603  page 130 : A = P3V3_STBY ; B = GND
C4D23  CAP_A  1.0UF 6.3V 10% X6S  pkg 0402V  page 102 : A = P3V3_DB1200_A ; B = GND
C2D28  CAP_A  22.0UF 4V 20% X6S  pkg 0603V  page 76 : A = PVCCMCP_CPU1 ; B = GND

(kicad_pcb
	(version 20260206)
	(generator "pcbnew")
	(generator_version "10.0")
	(general
		(thickness 1.6)
		(legacy_teardrops no)
	)
	(paper "A4")
	(title_block
		(title "Wiwynn_Tioga_Pass_MB.brd")
		(comment 1 "Tioga Pass / footprints 578-580 of 4770")
	)
	(layers
		(0 "F.Cu" signal "TOP")
		(4 "In1.Cu" signal "L2GND")
		(6 "In2.Cu" signal "L3")
		(8 "In3.Cu" signal "L4GND")
		(10 "In4.Cu" signal "L5")
		(12 "In5.Cu" signal "L6GND")
		(14 "In6.Cu" signal "L7VCC")
		(16 "In7.Cu" signal "L8VCC")
		(18 "In8.Cu" signal "L9GND")
		(20 "In9.Cu" signal "L10")
		(22 "In10.Cu" signal "L11GND")
		(24 "In11.Cu" signal "L12")
		(26 "In12.Cu" signal "L13GND")
		(2 "B.Cu" signal "BOTTOM")
		(9 "F.Adhes" user "F.Adhesive")
		(11 "B.Adhes" user "B.Adhesive")
		(13 "F.Paste" user "Package Geometry/Pastemask Top")
		(15 "B.Paste" user "Package Geometry/Pastemask Bottom")
		(5 "F.SilkS" user "Ref Des/Silkscreen Top")
		(7 "B.SilkS" user "Ref Des/Silkscreen Bottom")
		(1 "F.Mask" user "Board Geometry/Soldermask Top")
		(3 "B.Mask" user "Board Geometry/Soldermask Bottom")
		(17 "Dwgs.User" user "User.Drawings")
		(19 "Cmts.User" user "User.Comments")
		(21 "Eco1.User" user "User.Eco1")
		(23 "Eco2.User" user "User.Eco2")
		(25 "Edge.Cuts" user "Board Geometry/Outline")
		(27 "Margin" user)
		(31 "F.CrtYd" user "Package Geometry/Place Bound Top")
		(29 "B.CrtYd" user "Package Geometry/Place Bound Bottom")
		(35 "F.Fab" user "Ref Des/Assembly Top")
		(33 "B.Fab" user "Ref Des/Assembly Bottom")
	)
	(footprint ""
		(layer "F.Cu")
		(at 406.654 -93.280992 90)
		(property "Reference" "C8C6"
			(at 0 0 90)
			(layer "F.SilkS")
			(hide yes)
			(effects
				(font
					(size 1.27 1.27)
				)
			)
		)
		(property "Value" ""
			(at 0 0 90)
			(layer "F.Fab")
			(effects
				(font
					(size 1.27 1.27)
				)
			)
		)
		(duplicate_pad_numbers_are_jumpers no)
		(fp_poly
			(pts
				(xy -0.4953 -0.2032) (xy 0.4953 -0.2032) (xy 0.4953 1.6002) (xy -0.4953 1.6002)
			)
			(stroke
				(width 0)
				(type default)
			)
			(fill no)
			(layer "F.CrtYd")
		)
		(fp_line
			(start 0.4953 -0.2032)
			(end 0.4953 1.6002)
			(stroke
				(width 0.1)
				(type default)
			)
			(layer "F.Fab")
		)
		(fp_line
			(start -0.4953 -0.2032)
			(end 0.4953 -0.2032)
			(stroke
				(width 0.1)
				(type default)
			)
			(layer "F.Fab")
		)
		(fp_line
			(start 0.4953 1.6002)
			(end -0.4953 1.6002)
			(stroke
				(width 0.1)
				(type default)
			)
			(layer "F.Fab")
		)
		(fp_line
			(start -0.4953 1.6002)
			(end -0.4953 -0.2032)
			(stroke
				(width 0.1)
				(type default)
			)
			(layer "F.Fab")
		)
		(pad "1" smd rect
			(at 0 0 90)
			(size 0.762 0.889)
			(layers "F.Cu" "F.Mask" "F.Paste")
			(net "P3V3_STBY")
		)
		(pad "2" smd rect
			(at 0 1.397 90)
			(size 0.762 0.889)
			(layers "F.Cu" "F.Mask" "F.Paste")
			(net "GND")
		)
		(zone
			(layer "F.Cu")
			(hatch none 0.5)
			(connect_pads
				(clearance 0)
			)
			(min_thickness 0.25)
			(keepout
				(tracks not_allowed)
				(vias allowed)
				(pads allowed)
				(copperpour not_allowed)
				(footprints allowed)
			)
			(placement
				(enabled no)
				(sheetname "")
			)
			(fill
				(thermal_gap 0.5)
				(thermal_bridge_width 0.5)
				(island_removal_mode 0)
			)
			(polygon
				(pts
					(xy 407.0985 -92.899992) (xy 407.0985 -93.661992) (xy 407.6065 -93.661992) (xy 407.6065 -92.899992)
				)
			)
		)
	)
	(footprint ""
		(layer "F.Cu")
		(at 164.465 -74.803)
		(property "Reference" "C4D23"
			(at 0 0 0)
			(layer "F.SilkS")
			(hide yes)
			(effects
				(font
					(size 1.27 1.27)
				)
			)
		)
		(property "Value" ""
			(at 0 0 0)
			(layer "F.Fab")
			(effects
				(font
					(size 1.27 1.27)
				)
			)
		)
		(duplicate_pad_numbers_are_jumpers no)
		(fp_poly
			(pts
				(xy 0.3048 -0.1016) (xy 0.3048 0.9906) (xy -0.3048 0.9906) (xy -0.3048 -0.1016)
			)
			(stroke
				(width 0)
				(type default)
			)
			(fill no)
			(layer "F.CrtYd")
		)
		(fp_line
			(start -0.3048 -0.1016)
			(end -0.3048 0.9906)
			(stroke
				(width 0.1)
				(type default)
			)
			(layer "F.Fab")
		)
		(fp_line
			(start -0.3048 0.9906)
			(end 0.3048 0.9906)
			(stroke
				(width 0.1)
				(type default)
			)
			(layer "F.Fab")
		)
		(fp_line
			(start 0.3048 -0.1016)
			(end -0.3048 -0.1016)
			(stroke
				(width 0.1)
				(type default)
			)
			(layer "F.Fab")
		)
		(fp_line
			(start 0.3048 0.9906)
			(end 0.3048 -0.1016)
			(stroke
				(width 0.1)
				(type default)
			)
			(layer "F.Fab")
		)
		(pad "1" smd rect
			(at 0 0)
			(size 0.508 0.508)
			(layers "F.Cu" "F.Mask" "F.Paste")
			(net "P3V3_DB1200_A")
		)
		(pad "2" smd rect
			(at 0 0.889)
			(size 0.508 0.508)
			(layers "F.Cu" "F.Mask" "F.Paste")
			(net "GND")
		)
		(zone
			(layer "F.Cu")
			(hatch none 0.5)
			(connect_pads
				(clearance 0)
			)
			(min_thickness 0.25)
			(keepout
				(tracks allowed)
				(vias not_allowed)
				(pads allowed)
				(copperpour not_allowed)
				(footprints allowed)
			)
			(placement
				(enabled no)
				(sheetname "")
			)
			(fill
				(thermal_gap 0.5)
				(thermal_bridge_width 0.5)
				(island_removal_mode 0)
			)
			(polygon
				(pts
					(xy 164.211 -74.549) (xy 164.719 -74.549) (xy 164.719 -74.168) (xy 164.211 -74.168)
				)
			)
		)
		(zone
			(layer "F.Cu")
			(hatch none 0.5)
			(connect_pads
				(clearance 0)
			)
			(min_thickness 0.25)
			(keepout
				(tracks not_allowed)
				(vias allowed)
				(pads allowed)
				(copperpour not_allowed)
				(footprints allowed)
			)
			(placement
				(enabled no)
				(sheetname "")
			)
			(fill
				(thermal_gap 0.5)
				(thermal_bridge_width 0.5)
				(island_removal_mode 0)
			)
			(polygon
				(pts
					(xy 164.211 -74.168) (xy 164.719 -74.168) (xy 164.719 -74.549) (xy 164.211 -74.549)
				)
			)
		)
	)
	(footprint ""
		(layer "F.Cu")
		(at 104.40924 -77.636116)
		(property "Reference" "C2D28"
			(at 0 0 0)
			(layer "F.SilkS")
			(hide yes)
			(effects
				(font
					(size 1.27 1.27)
				)
			)
		)
		(property "Value" ""
			(at 0 0 0)
			(layer "F.Fab")
			(effects
				(font
					(size 1.27 1.27)
				)
			)
		)
		(duplicate_pad_numbers_are_jumpers no)
		(fp_poly
			(pts
				(xy -0.4953 -0.2032) (xy 0.4953 -0.2032) (xy 0.4953 1.6002) (xy -0.4953 1.6002)
			)
			(stroke
				(width 0)
				(type default)
			)
			(fill no)
			(layer "F.CrtYd")
		)
		(fp_line
			(start -0.4953 -0.2032)
			(end 0.4953 -0.2032)
			(stroke
				(width 0.1)
				(type default)
			)
			(layer "F.Fab")
		)
		(fp_line
			(start -0.4953 1.6002)
			(end -0.4953 -0.2032)
			(stroke
				(width 0.1)
				(type default)
			)
			(layer "F.Fab")
		)
		(fp_line
			(start 0.4953 -0.2032)
			(end 0.4953 1.6002)
			(stroke
				(width 0.1)
				(type default)
			)
			(layer "F.Fab")
		)
		(fp_line
			(start 0.4953 1.6002)
			(end -0.4953 1.6002)
			(stroke
				(width 0.1)
				(type default)
			)
			(layer "F.Fab")
		)
		(pad "1" smd rect
			(at 0 0)
			(size 0.762 0.889)
			(layers "F.Cu" "F.Mask" "F.Paste")
			(net "PVCCMCP_CPU1")
		)
		(pad "2" smd rect
			(at 0 1.397)
			(size 0.762 0.889)
			(layers "F.Cu" "F.Mask" "F.Paste")
			(net "GND")
		)
		(zone
			(layer "F.Cu")
			(hatch none 0.5)
			(connect_pads
				(clearance 0)
			)
			(min_thickness 0.25)
			(keepout
				(tracks not_allowed)
				(vias allowed)
				(pads allowed)
				(copperpour not_allowed)
				(footprints allowed)
			)
			(placement
				(enabled no)
				(sheetname "")
			)
			(fill
				(thermal_gap 0.5)
				(thermal_bridge_width 0.5)
				(island_removal_mode 0)
			)
			(polygon
				(pts
					(xy 104.02824 -77.191616) (xy 104.79024 -77.191616) (xy 104.79024 -76.683616) (xy 104.02824 -76.683616)
				)
			)
		)
	)
)
